(kicad_pcb
	(version 20260206)
	(generator "pcbnew")
	(generator_version "10.0")
	(general
		(thickness 1.6)
		(legacy_teardrops no)
	)
	(paper "A4")
	(title_block
		(title "01162023_DA0F0TEBIF0_F0T_Expander_BD_F_brd_V02_OCP.brd")
		(comment 1 "Grand Teton / footprints 6578-6584 of 9728")
	)
	(layers
		(0 "F.Cu" signal "TOP")
		(4 "In1.Cu" signal "GND")
		(6 "In2.Cu" signal "VCC")
		(8 "In3.Cu" signal "VCC1")
		(10 "In4.Cu" signal "GND1")
		(12 "In5.Cu" signal "IN1")
		(14 "In6.Cu" signal "GND2")
		(16 "In7.Cu" signal "IN2")
		(18 "In8.Cu" signal "GND3")
		(20 "In9.Cu" signal "IN3")
		(22 "In10.Cu" signal "GND4")
		(24 "In11.Cu" signal "IN4")
		(26 "In12.Cu" signal "GND5")
		(28 "In13.Cu" signal "IN5")
		(30 "In14.Cu" signal "GND6")
		(32 "In15.Cu" signal "IN6")
		(34 "In16.Cu" signal "GND7")
		(2 "B.Cu" signal "BOTTOM")
		(9 "F.Adhes" user "F.Adhesive")
		(11 "B.Adhes" user "B.Adhesive")
		(13 "F.Paste" user "Package Geometry/Pastemask Top")
		(15 "B.Paste" user "Package Geometry/Pastemask Bottom")
		(5 "F.SilkS" user "Ref Des/Silkscreen Top")
		(7 "B.SilkS" user "Ref Des/Silkscreen Bottom")
		(1 "F.Mask" user "Board Geometry/Soldermask Top")
		(3 "B.Mask" user "Board Geometry/Soldermask Bottom")
		(17 "Dwgs.User" user "User.Drawings")
		(19 "Cmts.User" user "User.Comments")
		(21 "Eco1.User" user "User.Eco1")
		(23 "Eco2.User" user "User.Eco2")
		(25 "Edge.Cuts" user "Board Geometry/Outline")
		(27 "Margin" user)
		(31 "F.CrtYd" user "Package Geometry/Place Bound Top")
		(29 "B.CrtYd" user "Package Geometry/Place Bound Bottom")
		(35 "F.Fab" user "Ref Des/Assembly Top")
		(33 "B.Fab" user "Ref Des/Assembly Bottom")
	)
	(footprint ""
		(layer "F.Cu")
		(at 58.176922 -378.572268)
		(property "Reference" "R1825"
			(at 0 0 0)
			(layer "F.SilkS")
			(hide yes)
			(effects
				(font
					(size 1.27 1.27)
				)
			)
		)
		(property "Value" ""
			(at 0 0 0)
			(layer "F.Fab")
			(effects
				(font
					(size 1.27 1.27)
				)
			)
		)
		(duplicate_pad_numbers_are_jumpers no)
		(fp_line
			(start -0.7874 -0.4064)
			(end 0.7874 -0.4064)
			(stroke
				(width 0.1524)
				(type default)
			)
			(layer "F.SilkS")
		)
		(fp_line
			(start -0.7874 0.4064)
			(end -0.7874 -0.4064)
			(stroke
				(width 0.1524)
				(type default)
			)
			(layer "F.SilkS")
		)
		(fp_line
			(start 0.7874 -0.4064)
			(end 0.7874 0.4064)
			(stroke
				(width 0.1524)
				(type default)
			)
			(layer "F.SilkS")
		)
		(fp_line
			(start 0.7874 0.4064)
			(end -0.7874 0.4064)
			(stroke
				(width 0.1524)
				(type default)
			)
			(layer "F.SilkS")
		)
		(fp_line
			(start -0.67945 -0.305054)
			(end -0.12065 -0.305054)
			(stroke
				(width 0.1)
				(type default)
			)
			(layer "F.Fab")
		)
		(fp_line
			(start -0.67945 0.3048)
			(end -0.67945 -0.305054)
			(stroke
				(width 0.1)
				(type default)
			)
			(layer "F.Fab")
		)
		(fp_line
			(start -0.12065 -0.305054)
			(end -0.12065 -0.2794)
			(stroke
				(width 0.1)
				(type default)
			)
			(layer "F.Fab")
		)
		(fp_line
			(start -0.12065 -0.2794)
			(end 0.12065 -0.2794)
			(stroke
				(width 0.1)
				(type default)
			)
			(layer "F.Fab")
		)
		(fp_line
			(start -0.12065 0.2794)
			(end -0.12065 0.3048)
			(stroke
				(width 0.1)
				(type default)
			)
			(layer "F.Fab")
		)
		(fp_line
			(start -0.12065 0.3048)
			(end -0.67945 0.3048)
			(stroke
				(width 0.1)
				(type default)
			)
			(layer "F.Fab")
		)
		(fp_line
			(start 0.120396 0.2794)
			(end -0.12065 0.2794)
			(stroke
				(width 0.1)
				(type default)
			)
			(layer "F.Fab")
		)
		(fp_line
			(start 0.120396 0.3048)
			(end 0.120396 0.2794)
			(stroke
				(width 0.1)
				(type default)
			)
			(layer "F.Fab")
		)
		(fp_line
			(start 0.12065 -0.3048)
			(end 0.67945 -0.3048)
			(stroke
				(width 0.1)
				(type default)
			)
			(layer "F.Fab")
		)
		(fp_line
			(start 0.12065 -0.2794)
			(end 0.12065 -0.3048)
			(stroke
				(width 0.1)
				(type default)
			)
			(layer "F.Fab")
		)
		(fp_line
			(start 0.67945 -0.3048)
			(end 0.67945 0.3048)
			(stroke
				(width 0.1)
				(type default)
			)
			(layer "F.Fab")
		)
		(fp_line
			(start 0.67945 0.3048)
			(end 0.120396 0.3048)
			(stroke
				(width 0.1)
				(type default)
			)
			(layer "F.Fab")
		)
		(pad "1" smd circle
			(at -0.40005 0)
			(size 0 0)
			(layers "F.Cu" "F.Mask" "F.Paste")
			(net "GPU_BASE_ID1_R")
		)
		(pad "2" smd circle
			(at 0.40005 0)
			(size 0 0)
			(layers "F.Cu" "F.Mask" "F.Paste")
			(net "GPU_BASE_ID1")
		)
	)
	(footprint ""
		(layer "F.Cu")
		(at 41.984168 -343.952322 90)
		(property "Reference" "C171"
			(at 0 0 90)
			(layer "F.SilkS")
			(hide yes)
			(effects
				(font
					(size 1.27 1.27)
				)
			)
		)
		(property "Value" ""
			(at 0 0 90)
			(layer "F.Fab")
			(effects
				(font
					(size 1.27 1.27)
				)
			)
		)
		(duplicate_pad_numbers_are_jumpers no)
		(fp_line
			(start 0.299974 -0.150114)
			(end 0.299974 0.150114)
			(stroke
				(width 0.1)
				(type default)
			)
			(layer "F.Fab")
		)
		(fp_line
			(start -0.299974 -0.150114)
			(end 0.299974 -0.150114)
			(stroke
				(width 0.1)
				(type default)
			)
			(layer "F.Fab")
		)
		(fp_line
			(start 0.299974 0.150114)
			(end -0.299974 0.150114)
			(stroke
				(width 0.1)
				(type default)
			)
			(layer "F.Fab")
		)
		(fp_line
			(start -0.299974 0.150114)
			(end -0.299974 -0.150114)
			(stroke
				(width 0.1)
				(type default)
			)
			(layer "F.Fab")
		)
		(pad "1" smd rect
			(at -0.2667 0 90)
			(size 0.3048 0.381)
			(layers "F.Cu" "F.Mask" "F.Paste")
			(net "P5E_PEX0_STN7_TX_DP<122>")
		)
		(pad "2" smd rect
			(at 0.2667 0 90)
			(size 0.3048 0.381)
			(layers "F.Cu" "F.Mask" "F.Paste")
			(net "P5E_PEX0_STN7_TX_C_DP<122>")
		)
	)
	(footprint ""
		(layer "F.Cu")
		(at 115.83035 -309.749952 -90)
		(property "Reference" "R6453"
			(at 0 0 270)
			(layer "F.SilkS")
			(hide yes)
			(effects
				(font
					(size 1.27 1.27)
				)
			)
		)
		(property "Value" ""
			(at 0 0 270)
			(layer "F.Fab")
			(effects
				(font
					(size 1.27 1.27)
				)
			)
		)
		(duplicate_pad_numbers_are_jumpers no)
		(fp_line
			(start -0.7874 0.4064)
			(end -0.7874 -0.4064)
			(stroke
				(width 0.1524)
				(type default)
			)
			(layer "F.SilkS")
		)
		(fp_line
			(start 0.7874 0.4064)
			(end -0.7874 0.4064)
			(stroke
				(width 0.1524)
				(type default)
			)
			(layer "F.SilkS")
		)
		(fp_line
			(start -0.7874 -0.4064)
			(end 0.7874 -0.4064)
			(stroke
				(width 0.1524)
				(type default)
			)
			(layer "F.SilkS")
		)
		(fp_line
			(start 0.7874 -0.4064)
			(end 0.7874 0.4064)
			(stroke
				(width 0.1524)
				(type default)
			)
			(layer "F.SilkS")
		)
		(fp_line
			(start -0.67945 0.3048)
			(end -0.67945 -0.305054)
			(stroke
				(width 0.1)
				(type default)
			)
			(layer "F.Fab")
		)
		(fp_line
			(start -0.12065 0.3048)
			(end -0.67945 0.3048)
			(stroke
				(width 0.1)
				(type default)
			)
			(layer "F.Fab")
		)
		(fp_line
			(start 0.120396 0.3048)
			(end 0.120396 0.2794)
			(stroke
				(width 0.1)
				(type default)
			)
			(layer "F.Fab")
		)
		(fp_line
			(start 0.67945 0.3048)
			(end 0.120396 0.3048)
			(stroke
				(width 0.1)
				(type default)
			)
			(layer "F.Fab")
		)
		(fp_line
			(start -0.12065 0.2794)
			(end -0.12065 0.3048)
			(stroke
				(width 0.1)
				(type default)
			)
			(layer "F.Fab")
		)
		(fp_line
			(start 0.120396 0.2794)
			(end -0.12065 0.2794)
			(stroke
				(width 0.1)
				(type default)
			)
			(layer "F.Fab")
		)
		(fp_line
			(start -0.12065 -0.2794)
			(end 0.12065 -0.2794)
			(stroke
				(width 0.1)
				(type default)
			)
			(layer "F.Fab")
		)
		(fp_line
			(start 0.12065 -0.2794)
			(end 0.12065 -0.3048)
			(stroke
				(width 0.1)
				(type default)
			)
			(layer "F.Fab")
		)
		(fp_line
			(start 0.12065 -0.3048)
			(end 0.67945 -0.3048)
			(stroke
				(width 0.1)
				(type default)
			)
			(layer "F.Fab")
		)
		(fp_line
			(start 0.67945 -0.3048)
			(end 0.67945 0.3048)
			(stroke
				(width 0.1)
				(type default)
			)
			(layer "F.Fab")
		)
		(fp_line
			(start -0.67945 -0.305054)
			(end -0.12065 -0.305054)
			(stroke
				(width 0.1)
				(type default)
			)
			(layer "F.Fab")
		)
		(fp_line
			(start -0.12065 -0.305054)
			(end -0.12065 -0.2794)
			(stroke
				(width 0.1)
				(type default)
			)
			(layer "F.Fab")
		)
		(pad "1" smd circle
			(at -0.40005 0 270)
			(size 0 0)
			(layers "F.Cu" "F.Mask" "F.Paste")
			(net "P0V8_SERDES_VDDA_PEX0")
		)
		(pad "2" smd circle
			(at 0.40005 0 270)
			(size 0 0)
			(layers "F.Cu" "F.Mask" "F.Paste")
			(net "P0V8_SERDES_VDDA_PEX0_C4")
		)
	)
	(footprint ""
		(layer "F.Cu")
		(at 244.12194 -254.097282 -90)
		(property "Reference" "C4353"
			(at 0 0 270)
			(layer "F.SilkS")
			(hide yes)
			(effects
				(font
					(size 1.27 1.27)
				)
			)
		)
		(property "Value" ""
			(at 0 0 270)
			(layer "F.Fab")
			(effects
				(font
					(size 1.27 1.27)
				)
			)
		)
		(duplicate_pad_numbers_are_jumpers no)
		(fp_line
			(start -1.2954 0.5842)
			(end -1.2954 -0.5842)
			(stroke
				(width 0.1524)
				(type default)
			)
			(layer "F.SilkS")
		)
		(fp_line
			(start 1.2954 0.5842)
			(end -1.2954 0.5842)
			(stroke
				(width 0.1524)
				(type default)
			)
			(layer "F.SilkS")
		)
		(fp_line
			(start -1.2954 -0.5842)
			(end 1.2954 -0.5842)
			(stroke
				(width 0.1524)
				(type default)
			)
			(layer "F.SilkS")
		)
		(fp_line
			(start 1.2954 -0.5842)
			(end 1.2954 0.5842)
			(stroke
				(width 0.1524)
				(type default)
			)
			(layer "F.SilkS")
		)
		(fp_line
			(start -0.8636 0.4572)
			(end -0.8636 0.4064)
			(stroke
				(width 0.1)
				(type default)
			)
			(layer "F.Fab")
		)
		(fp_line
			(start 0.8636 0.4572)
			(end -0.8636 0.4572)
			(stroke
				(width 0.1)
				(type default)
			)
			(layer "F.Fab")
		)
		(fp_line
			(start -1.1938 0.4064)
			(end -1.1938 -0.4064)
			(stroke
				(width 0.1)
				(type default)
			)
			(layer "F.Fab")
		)
		(fp_line
			(start -0.8636 0.4064)
			(end -1.1938 0.4064)
			(stroke
				(width 0.1)
				(type default)
			)
			(layer "F.Fab")
		)
		(fp_line
			(start 0.8636 0.4064)
			(end 0.8636 0.4572)
			(stroke
				(width 0.1)
				(type default)
			)
			(layer "F.Fab")
		)
		(fp_line
			(start 1.1938 0.4064)
			(end 0.8636 0.4064)
			(stroke
				(width 0.1)
				(type default)
			)
			(layer "F.Fab")
		)
		(fp_line
			(start -1.1938 -0.4064)
			(end -0.8636 -0.4064)
			(stroke
				(width 0.1)
				(type default)
			)
			(layer "F.Fab")
		)
		(fp_line
			(start -0.8636 -0.4064)
			(end -0.8636 -0.4572)
			(stroke
				(width 0.1)
				(type default)
			)
			(layer "F.Fab")
		)
		(fp_line
			(start 0.8636 -0.4064)
			(end 1.1938 -0.4064)
			(stroke
				(width 0.1)
				(type default)
			)
			(layer "F.Fab")
		)
		(fp_line
			(start 1.1938 -0.4064)
			(end 1.1938 0.4064)
			(stroke
				(width 0.1)
				(type default)
			)
			(layer "F.Fab")
		)
		(fp_line
			(start -0.8636 -0.4572)
			(end 0.8636 -0.4572)
			(stroke
				(width 0.1)
				(type default)
			)
			(layer "F.Fab")
		)
		(fp_line
			(start 0.8636 -0.4572)
			(end 0.8636 -0.4064)
			(stroke
				(width 0.1)
				(type default)
			)
			(layer "F.Fab")
		)
		(pad "1" smd rect
			(at -0.7366 0 180)
			(size 0.7112 0.8128)
			(layers "F.Cu" "F.Mask" "F.Paste")
			(net "P1V25_SERDES_VDDPLL_PEX2_C7")
		)
		(pad "2" smd rect
			(at 0.7366 0 180)
			(size 0.7112 0.8128)
			(layers "F.Cu" "F.Mask" "F.Paste")
			(net "GND")
		)
	)
	(footprint ""
		(layer "F.Cu")
		(at 143.226282 -39.73576 -90)
		(property "Reference" "R5554"
			(at 0 0 270)
			(layer "F.SilkS")
			(hide yes)
			(effects
				(font
					(size 1.27 1.27)
				)
			)
		)
		(property "Value" ""
			(at 0 0 270)
			(layer "F.Fab")
			(effects
				(font
					(size 1.27 1.27)
				)
			)
		)
		(duplicate_pad_numbers_are_jumpers no)
		(fp_line
			(start -0.7874 0.4064)
			(end -0.7874 -0.4064)
			(stroke
				(width 0.1524)
				(type default)
			)
			(layer "F.SilkS")
		)
		(fp_line
			(start 0.7874 0.4064)
			(end -0.7874 0.4064)
			(stroke
				(width 0.1524)
				(type default)
			)
			(layer "F.SilkS")
		)
		(fp_line
			(start -0.7874 -0.4064)
			(end 0.7874 -0.4064)
			(stroke
				(width 0.1524)
				(type default)
			)
			(layer "F.SilkS")
		)
		(fp_line
			(start 0.7874 -0.4064)
			(end 0.7874 0.4064)
			(stroke
				(width 0.1524)
				(type default)
			)
			(layer "F.SilkS")
		)
		(fp_line
			(start -0.67945 0.3048)
			(end -0.67945 -0.305054)
			(stroke
				(width 0.1)
				(type default)
			)
			(layer "F.Fab")
		)
		(fp_line
			(start -0.12065 0.3048)
			(end -0.67945 0.3048)
			(stroke
				(width 0.1)
				(type default)
			)
			(layer "F.Fab")
		)
		(fp_line
			(start 0.120396 0.3048)
			(end 0.120396 0.2794)
			(stroke
				(width 0.1)
				(type default)
			)
			(layer "F.Fab")
		)
		(fp_line
			(start 0.67945 0.3048)
			(end 0.120396 0.3048)
			(stroke
				(width 0.1)
				(type default)
			)
			(layer "F.Fab")
		)
		(fp_line
			(start -0.12065 0.2794)
			(end -0.12065 0.3048)
			(stroke
				(width 0.1)
				(type default)
			)
			(layer "F.Fab")
		)
		(fp_line
			(start 0.120396 0.2794)
			(end -0.12065 0.2794)
			(stroke
				(width 0.1)
				(type default)
			)
			(layer "F.Fab")
		)
		(fp_line
			(start -0.12065 -0.2794)
			(end 0.12065 -0.2794)
			(stroke
				(width 0.1)
				(type default)
			)
			(layer "F.Fab")
		)
		(fp_line
			(start 0.12065 -0.2794)
			(end 0.12065 -0.3048)
			(stroke
				(width 0.1)
				(type default)
			)
			(layer "F.Fab")
		)
		(fp_line
			(start 0.12065 -0.3048)
			(end 0.67945 -0.3048)
			(stroke
				(width 0.1)
				(type default)
			)
			(layer "F.Fab")
		)
		(fp_line
			(start 0.67945 -0.3048)
			(end 0.67945 0.3048)
			(stroke
				(width 0.1)
				(type default)
			)
			(layer "F.Fab")
		)
		(fp_line
			(start -0.67945 -0.305054)
			(end -0.12065 -0.305054)
			(stroke
				(width 0.1)
				(type default)
			)
			(layer "F.Fab")
		)
		(fp_line
			(start -0.12065 -0.305054)
			(end -0.12065 -0.2794)
			(stroke
				(width 0.1)
				(type default)
			)
			(layer "F.Fab")
		)
		(pad "1" smd circle
			(at -0.40005 0 270)
			(size 0 0)
			(layers "F.Cu" "F.Mask" "F.Paste")
			(net "P3V3_AUX")
		)
		(pad "2" smd circle
			(at 0.40005 0 270)
			(size 0 0)
			(layers "F.Cu" "F.Mask" "F.Paste")
			(net "SSD5_AUX_P3V3_EN")
		)
	)
	(footprint ""
		(layer "F.Cu")
		(at 142.559532 -22.955504 90)
		(property "Reference" "R1671"
			(at 0 0 90)
			(layer "F.SilkS")
			(hide yes)
			(effects
				(font
					(size 1.27 1.27)
				)
			)
		)
		(property "Value" ""
			(at 0 0 90)
			(layer "F.Fab")
			(effects
				(font
					(size 1.27 1.27)
				)
			)
		)
		(duplicate_pad_numbers_are_jumpers no)
		(fp_line
			(start 0.7874 -0.4064)
			(end 0.7874 0.4064)
			(stroke
				(width 0.1524)
				(type default)
			)
			(layer "F.SilkS")
		)
		(fp_line
			(start -0.7874 -0.4064)
			(end 0.7874 -0.4064)
			(stroke
				(width 0.1524)
				(type default)
			)
			(layer "F.SilkS")
		)
		(fp_line
			(start 0.7874 0.4064)
			(end -0.7874 0.4064)
			(stroke
				(width 0.1524)
				(type default)
			)
			(layer "F.SilkS")
		)
		(fp_line
			(start -0.7874 0.4064)
			(end -0.7874 -0.4064)
			(stroke
				(width 0.1524)
				(type default)
			)
			(layer "F.SilkS")
		)
		(fp_line
			(start -0.12065 -0.305054)
			(end -0.12065 -0.2794)
			(stroke
				(width 0.1)
				(type default)
			)
			(layer "F.Fab")
		)
		(fp_line
			(start -0.67945 -0.305054)
			(end -0.12065 -0.305054)
			(stroke
				(width 0.1)
				(type default)
			)
			(layer "F.Fab")
		)
		(fp_line
			(start 0.67945 -0.3048)
			(end 0.67945 0.3048)
			(stroke
				(width 0.1)
				(type default)
			)
			(layer "F.Fab")
		)
		(fp_line
			(start 0.12065 -0.3048)
			(end 0.67945 -0.3048)
			(stroke
				(width 0.1)
				(type default)
			)
			(layer "F.Fab")
		)
		(fp_line
			(start 0.12065 -0.2794)
			(end 0.12065 -0.3048)
			(stroke
				(width 0.1)
				(type default)
			)
			(layer "F.Fab")
		)
		(fp_line
			(start -0.12065 -0.2794)
			(end 0.12065 -0.2794)
			(stroke
				(width 0.1)
				(type default)
			)
			(layer "F.Fab")
		)
		(fp_line
			(start 0.120396 0.2794)
			(end -0.12065 0.2794)
			(stroke
				(width 0.1)
				(type default)
			)
			(layer "F.Fab")
		)
		(fp_line
			(start -0.12065 0.2794)
			(end -0.12065 0.3048)
			(stroke
				(width 0.1)
				(type default)
			)
			(layer "F.Fab")
		)
		(fp_line
			(start 0.67945 0.3048)
			(end 0.120396 0.3048)
			(stroke
				(width 0.1)
				(type default)
			)
			(layer "F.Fab")
		)
		(fp_line
			(start 0.120396 0.3048)
			(end 0.120396 0.2794)
			(stroke
				(width 0.1)
				(type default)
			)
			(layer "F.Fab")
		)
		(fp_line
			(start -0.12065 0.3048)
			(end -0.67945 0.3048)
			(stroke
				(width 0.1)
				(type default)
			)
			(layer "F.Fab")
		)
		(fp_line
			(start -0.67945 0.3048)
			(end -0.67945 -0.305054)
			(stroke
				(width 0.1)
				(type default)
			)
			(layer "F.Fab")
		)
		(pad "1" smd circle
			(at -0.40005 0 90)
			(size 0 0)
			(layers "F.Cu" "F.Mask" "F.Paste")
			(net "SMB_BIC_I2C9_MUX0_SSD4_R_SCL")
		)
		(pad "2" smd circle
			(at 0.40005 0 90)
			(size 0 0)
			(layers "F.Cu" "F.Mask" "F.Paste")
			(net "SMB_ISO_SSD4_SCL")
		)
	)
	(footprint ""
		(layer "F.Cu")
		(at 144.923764 -306.366418 45)
		(property "Reference" "R1319"
			(at 0 0 45)
			(layer "F.SilkS")
			(hide yes)
			(effects
				(font
					(size 1.27 1.27)
				)
			)
		)
		(property "Value" ""
			(at 0 0 45)
			(layer "F.Fab")
			(effects
				(font
					(size 1.27 1.27)
				)
			)
		)
		(duplicate_pad_numbers_are_jumpers no)
		(fp_line
			(start -0.787389 -0.406267)
			(end 0.787389 -0.406267)
			(stroke
				(width 0.1524)
				(type default)
			)
			(layer "F.SilkS")
		)
		(fp_line
			(start -0.787389 0.406267)
			(end -0.787389 -0.406267)
			(stroke
				(width 0.1524)
				(type default)
			)
			(layer "F.SilkS")
		)
		(fp_line
			(start 0.787389 -0.406267)
			(end 0.787389 0.406267)
			(stroke
				(width 0.1524)
				(type default)
			)
			(layer "F.SilkS")
		)
		(fp_line
			(start 0.787389 0.406267)
			(end -0.787389 0.406267)
			(stroke
				(width 0.1524)
				(type default)
			)
			(layer "F.SilkS")
		)
		(fp_line
			(start -0.679446 -0.305149)
			(end -0.120695 -0.304969)
			(stroke
				(width 0.1)
				(type default)
			)
			(layer "F.Fab")
		)
		(fp_line
			(start -0.120695 -0.304969)
			(end -0.120695 -0.279466)
			(stroke
				(width 0.1)
				(type default)
			)
			(layer "F.Fab")
		)
		(fp_line
			(start -0.120695 -0.279466)
			(end 0.120695 -0.279466)
			(stroke
				(width 0.1)
				(type default)
			)
			(layer "F.Fab")
		)
		(fp_line
			(start -0.679446 0.30479)
			(end -0.679446 -0.305149)
			(stroke
				(width 0.1)
				(type default)
			)
			(layer "F.Fab")
		)
		(fp_line
			(start 0.120515 -0.30479)
			(end 0.679446 -0.30479)
			(stroke
				(width 0.1)
				(type default)
			)
			(layer "F.Fab")
		)
		(fp_line
			(start 0.120695 -0.279466)
			(end 0.120515 -0.30479)
			(stroke
				(width 0.1)
				(type default)
			)
			(layer "F.Fab")
		)
		(fp_line
			(start -0.120695 0.279466)
			(end -0.120515 0.30479)
			(stroke
				(width 0.1)
				(type default)
			)
			(layer "F.Fab")
		)
		(fp_line
			(start -0.120515 0.30479)
			(end -0.679446 0.30479)
			(stroke
				(width 0.1)
				(type default)
			)
			(layer "F.Fab")
		)
		(fp_line
			(start 0.679446 -0.30479)
			(end 0.679446 0.30479)
			(stroke
				(width 0.1)
				(type default)
			)
			(layer "F.Fab")
		)
		(fp_line
			(start 0.120335 0.279466)
			(end -0.120695 0.279466)
			(stroke
				(width 0.1)
				(type default)
			)
			(layer "F.Fab")
		)
		(fp_line
			(start 0.120515 0.30479)
			(end 0.120335 0.279466)
			(stroke
				(width 0.1)
				(type default)
			)
			(layer "F.Fab")
		)
		(fp_line
			(start 0.679446 0.30479)
			(end 0.120515 0.30479)
			(stroke
				(width 0.1)
				(type default)
			)
			(layer "F.Fab")
		)
		(pad "1" smd circle
			(at -0.40005 0 45)
			(size 0 0)
			(layers "F.Cu" "F.Mask" "F.Paste")
			(net "GND")
		)
		(pad "2" smd circle
			(at 0.40005 0 45)
			(size 0 0)
			(layers "F.Cu" "F.Mask" "F.Paste")
			(net "PEX1_DFT_IDDT")
		)
	)
)
